# T6G (Grand Teton) — schematic netlist excerpt (pin names and nets, part order shuffled) for the footprints in the layout excerpt that follows; sources: Cadence DE-HDL packaged netlist, KiCad conversion of 04192023_DAF0TMB3IC0_F0TG_MB_C_brd_V02_OCP.brd

C2523  Q_CAP  22UF 4V 20% X6S  pkg C0402  page 71 : A = PVDD18_S5_P0 ; B = GND

U47  PI3CSW12ZUAEX  IC  pkg UQFN10_0-5_2X1-5  page 186
  \1d+\  = SMB_RT_CPU0_P2_ROM_MUX_1D_SCL
  \1d-\  = SMB_RT_CPU0_P2_ROM_MUX_1D_SDA
  \2d+\  = SMB_RT_CPU0_P2_ROM_MUX_2D_SCL
  \2d-\  = SMB_RT_CPU0_P2_ROM_MUX_2D_SDA
  GND  = GND
  \oe#\  = RT_ROM_MUX8_OE_N
  \d-\  = SMB_RT_CPU0_P2_ROM_R_SDA
  \d+\  = SMB_RT_CPU0_P2_ROM_R_SCL
  S  = FM_SMB_RT_ROM_MUX8_SEL
  VDD  = P3V3_AUX

C1039  Q_CAP  1UF 4V 20% X6S  pkg 0201  page 312 : A = P0V9_CPU0_RT3_2A ; B = GND

(kicad_pcb
	(version 20260206)
	(generator "pcbnew")
	(generator_version "10.0")
	(general
		(thickness 1.6)
		(legacy_teardrops no)
	)
	(paper "A4")
	(title_block
		(title "04192023_DAF0TMB3IC0_F0TG_MB_C_brd_V02_OCP.brd")
		(comment 1 "Grand Teton / footprints 5122-5124 of 8354")
	)
	(layers
		(0 "F.Cu" signal "TOP")
		(4 "In1.Cu" signal "GND")
		(6 "In2.Cu" signal "IN1")
		(8 "In3.Cu" signal "GND1")
		(10 "In4.Cu" signal "IN2")
		(12 "In5.Cu" signal "GND2")
		(14 "In6.Cu" signal "IN3")
		(16 "In7.Cu" signal "GND3")
		(18 "In8.Cu" signal "VCC")
		(20 "In9.Cu" signal "VCC1")
		(22 "In10.Cu" signal "GND4")
		(24 "In11.Cu" signal "IN4")
		(26 "In12.Cu" signal "GND5")
		(28 "In13.Cu" signal "IN5")
		(30 "In14.Cu" signal "GND6")
		(32 "In15.Cu" signal "IN6")
		(34 "In16.Cu" signal "GND7")
		(2 "B.Cu" signal "BOTTOM")
		(9 "F.Adhes" user "F.Adhesive")
		(11 "B.Adhes" user "B.Adhesive")
		(13 "F.Paste" user "Package Geometry/Pastemask Top")
		(15 "B.Paste" user "Package Geometry/Pastemask Bottom")
		(5 "F.SilkS" user "Ref Des/Silkscreen Top")
		(7 "B.SilkS" user "Ref Des/Silkscreen Bottom")
		(1 "F.Mask" user "Board Geometry/Soldermask Top")
		(3 "B.Mask" user "Board Geometry/Soldermask Bottom")
		(17 "Dwgs.User" user "User.Drawings")
		(19 "Cmts.User" user "User.Comments")
		(21 "Eco1.User" user "User.Eco1")
		(23 "Eco2.User" user "User.Eco2")
		(25 "Edge.Cuts" user "Board Geometry/Outline")
		(27 "Margin" user)
		(31 "F.CrtYd" user "Package Geometry/Place Bound Top")
		(29 "B.CrtYd" user "Package Geometry/Place Bound Bottom")
		(35 "F.Fab" user "Ref Des/Assembly Top")
		(33 "B.Fab" user "Ref Des/Assembly Bottom")
	)
	(footprint ""
		(layer "B.Cu")
		(at 386.078476 -395.148562 90)
		(property "Reference" "C1039"
			(at 0 0 90)
			(layer "B.SilkS")
			(hide yes)
			(effects
				(font
					(size 1.27 1.27)
				)
				(justify mirror)
			)
		)
		(property "Value" ""
			(at 0 0 90)
			(layer "B.Fab")
			(effects
				(font
					(size 1.27 1.27)
				)
				(justify mirror)
			)
		)
		(duplicate_pad_numbers_are_jumpers no)
		(fp_line
			(start 0.299974 -0.150114)
			(end -0.299974 -0.150114)
			(stroke
				(width 0.1)
				(type default)
			)
			(layer "B.Fab")
		)
		(fp_line
			(start -0.299974 -0.150114)
			(end -0.299974 0.150114)
			(stroke
				(width 0.1)
				(type default)
			)
			(layer "B.Fab")
		)
		(fp_line
			(start 0.299974 0.150114)
			(end 0.299974 -0.150114)
			(stroke
				(width 0.1)
				(type default)
			)
			(layer "B.Fab")
		)
		(fp_line
			(start -0.299974 0.150114)
			(end 0.299974 0.150114)
			(stroke
				(width 0.1)
				(type default)
			)
			(layer "B.Fab")
		)
		(pad "1" smd rect
			(at 0.2667 0 270)
			(size 0.3048 0.381)
			(layers "B.Cu" "B.Mask" "B.Paste")
			(net "P0V9_CPU0_RT3_2A")
		)
		(pad "2" smd rect
			(at -0.2667 0 270)
			(size 0.3048 0.381)
			(layers "B.Cu" "B.Mask" "B.Paste")
			(net "GND")
		)
	)
	(footprint ""
		(layer "B.Cu")
		(at 421.90289 -426.765974)
		(property "Reference" "U47"
			(at -1.528826 -2.937002 0)
			(unlocked yes)
			(layer "B.SilkS")
			(effects
				(font
					(size 0.7874 0.5842)
					(thickness 0.1524)
				)
				(justify mirror)
			)
		)
		(property "Value" ""
			(at 0 0 0)
			(layer "B.Fab")
			(effects
				(font
					(size 1.27 1.27)
				)
				(justify mirror)
			)
		)
		(duplicate_pad_numbers_are_jumpers no)
		(fp_line
			(start -1.03378 -1.284478)
			(end -1.03378 1.284478)
			(stroke
				(width 0.1524)
				(type default)
			)
			(layer "B.SilkS")
		)
		(fp_line
			(start -1.03378 1.284478)
			(end 1.03378 1.284478)
			(stroke
				(width 0.1524)
				(type default)
			)
			(layer "B.SilkS")
		)
		(fp_line
			(start 1.03378 -1.284478)
			(end -1.03378 -1.284478)
			(stroke
				(width 0.1524)
				(type default)
			)
			(layer "B.SilkS")
		)
		(fp_line
			(start 1.03378 1.284478)
			(end 1.03378 -1.284478)
			(stroke
				(width 0.1524)
				(type default)
			)
			(layer "B.SilkS")
		)
		(fp_poly
			(pts
				(xy 1.266698 -0.776732) (xy 1.871726 -0.474218) (xy 1.871726 -1.079246)
			)
			(stroke
				(width 0)
				(type default)
			)
			(fill yes)
			(layer "B.SilkS")
		)
		(fp_line
			(start -0.774954 -1.02489)
			(end -0.774954 1.02489)
			(stroke
				(width 0.1)
				(type default)
			)
			(layer "B.Fab")
		)
		(fp_line
			(start -0.774954 1.02489)
			(end 0.774954 1.02489)
			(stroke
				(width 0.1)
				(type default)
			)
			(layer "B.Fab")
		)
		(fp_line
			(start 0.774954 -1.02489)
			(end -0.774954 -1.02489)
			(stroke
				(width 0.1)
				(type default)
			)
			(layer "B.Fab")
		)
		(fp_line
			(start 0.774954 1.02489)
			(end 0.774954 -1.02489)
			(stroke
				(width 0.1)
				(type default)
			)
			(layer "B.Fab")
		)
		(fp_poly
			(pts
				(xy 1.201674 -0.750062) (xy 1.806702 -0.447548) (xy 1.806702 -1.052576)
			)
			(stroke
				(width 0)
				(type default)
			)
			(fill yes)
			(layer "B.Fab")
		)
		(pad "1" smd rect
			(at 0.64008 -0.750062 90)
			(size 0.3048 0.5334)
			(layers "B.Cu" "B.Mask" "B.Paste")
			(net "SMB_RT_CPU0_P2_ROM_MUX_1D_SCL")
		)
		(pad "2" smd rect
			(at 0.64008 -0.249936 90)
			(size 0.254 0.5334)
			(layers "B.Cu" "B.Mask" "B.Paste")
			(net "SMB_RT_CPU0_P2_ROM_MUX_1D_SDA")
		)
		(pad "3" smd rect
			(at 0.64008 0.249936 90)
			(size 0.254 0.5334)
			(layers "B.Cu" "B.Mask" "B.Paste")
			(net "SMB_RT_CPU0_P2_ROM_MUX_2D_SCL")
		)
		(pad "4" smd rect
			(at 0.64008 0.750062 90)
			(size 0.3048 0.5334)
			(layers "B.Cu" "B.Mask" "B.Paste")
			(net "SMB_RT_CPU0_P2_ROM_MUX_2D_SDA")
		)
		(pad "5" smd rect
			(at 0 0.839978 180)
			(size 0.3302 0.635)
			(layers "B.Cu" "B.Mask" "B.Paste")
			(net "GND")
		)
		(pad "6" smd rect
			(at -0.64008 0.750062 90)
			(size 0.3048 0.5334)
			(layers "B.Cu" "B.Mask" "B.Paste")
			(net "RT_ROM_MUX8_OE_N")
		)
		(pad "7" smd rect
			(at -0.64008 0.249936 90)
			(size 0.254 0.5334)
			(layers "B.Cu" "B.Mask" "B.Paste")
			(net "SMB_RT_CPU0_P2_ROM_R_SDA")
		)
		(pad "8" smd rect
			(at -0.64008 -0.249936 90)
			(size 0.254 0.5334)
			(layers "B.Cu" "B.Mask" "B.Paste")
			(net "SMB_RT_CPU0_P2_ROM_R_SCL")
		)
		(pad "9" smd rect
			(at -0.64008 -0.750062 90)
			(size 0.3048 0.5334)
			(layers "B.Cu" "B.Mask" "B.Paste")
			(net "FM_SMB_RT_ROM_MUX8_SEL")
		)
		(pad "10" smd rect
			(at 0 -0.839978 180)
			(size 0.3302 0.635)
			(layers "B.Cu" "B.Mask" "B.Paste")
			(net "P3V3_AUX")
		)
	)
	(footprint ""
		(layer "B.Cu")
		(at 347.008958 -254.06731 180)
		(property "Reference" "C2523"
			(at 0 0 0)
			(layer "B.SilkS")
			(hide yes)
			(effects
				(font
					(size 1.27 1.27)
				)
				(justify mirror)
			)
		)
		(property "Value" ""
			(at 0 0 0)
			(layer "B.Fab")
			(effects
				(font
					(size 1.27 1.27)
				)
				(justify mirror)
			)
		)
		(duplicate_pad_numbers_are_jumpers no)
		(fp_line
			(start 0.7874 0.4064)
			(end 0.7874 -0.4064)
			(stroke
				(width 0.1524)
				(type default)
			)
			(layer "B.SilkS")
		)
		(fp_line
			(start 0.7874 -0.4064)
			(end -0.7874 -0.4064)
			(stroke
				(width 0.1524)
				(type default)
			)
			(layer "B.SilkS")
		)
		(fp_line
			(start -0.7874 0.4064)
			(end 0.7874 0.4064)
			(stroke
				(width 0.1524)
				(type default)
			)
			(layer "B.SilkS")
		)
		(fp_line
			(start -0.7874 -0.4064)
			(end -0.7874 0.4064)
			(stroke
				(width 0.1524)
				(type default)
			)
			(layer "B.SilkS")
		)
		(fp_line
			(start 0.67945 0.3048)
			(end 0.67945 -0.305054)
			(stroke
				(width 0.1)
				(type default)
			)
			(layer "B.Fab")
		)
		(fp_line
			(start 0.67945 -0.305054)
			(end 0.12065 -0.305054)
			(stroke
				(width 0.1)
				(type default)
			)
			(layer "B.Fab")
		)
		(fp_line
			(start 0.12065 0.3048)
			(end 0.67945 0.3048)
			(stroke
				(width 0.1)
				(type default)
			)
			(layer "B.Fab")
		)
		(fp_line
			(start 0.12065 0.2794)
			(end 0.12065 0.3048)
			(stroke
				(width 0.1)
				(type default)
			)
			(layer "B.Fab")
		)
		(fp_line
			(start 0.12065 -0.2794)
			(end -0.12065 -0.2794)
			(stroke
				(width 0.1)
				(type default)
			)
			(layer "B.Fab")
		)
		(fp_line
			(start 0.12065 -0.305054)
			(end 0.12065 -0.2794)
			(stroke
				(width 0.1)
				(type default)
			)
			(layer "B.Fab")
		)
		(fp_line
			(start -0.120396 0.3048)
			(end -0.120396 0.2794)
			(stroke
				(width 0.1)
				(type default)
			)
			(layer "B.Fab")
		)
		(fp_line
			(start -0.120396 0.2794)
			(end 0.12065 0.2794)
			(stroke
				(width 0.1)
				(type default)
			)
			(layer "B.Fab")
		)
		(fp_line
			(start -0.12065 -0.2794)
			(end -0.12065 -0.3048)
			(stroke
				(width 0.1)
				(type default)
			)
			(layer "B.Fab")
		)
		(fp_line
			(start -0.12065 -0.3048)
			(end -0.67945 -0.3048)
			(stroke
				(width 0.1)
				(type default)
			)
			(layer "B.Fab")
		)
		(fp_line
			(start -0.67945 0.3048)
			(end -0.120396 0.3048)
			(stroke
				(width 0.1)
				(type default)
			)
			(layer "B.Fab")
		)
		(fp_line
			(start -0.67945 -0.3048)
			(end -0.67945 0.3048)
			(stroke
				(width 0.1)
				(type default)
			)
			(layer "B.Fab")
		)
		(pad "1" smd circle
			(at 0.40005 0)
			(size 0 0)
			(layers "B.Cu" "B.Mask" "B.Paste")
			(net "PVDD18_S5_P0")
		)
		(pad "2" smd circle
			(at -0.40005 0)
			(size 0 0)
			(layers "B.Cu" "B.Mask" "B.Paste")
			(net "GND")
		)
	)
)
